# T6G (Grand Teton) — schematic netlist excerpt (pin names and nets, part order shuffled) for the footprints in the layout excerpt that follows; sources: Cadence DE-HDL packaged netlist, KiCad conversion of 04192023_DAF0TMB3IC0_F0TG_MB_C_brd_V02_OCP.brd

R2916  Q_RES  4.7K 5% EMPTY  pkg 0402LF  page 130 : A = RST_SWB_BIC_R_N ; B = GND
R6113  Q_RES  33.2 1% CHIP  pkg 0402LF  page 85 : A = RST_PERST_CPU1_SWB_N ; B = RST_PERST_CPU1_SWB_R_N

(kicad_pcb
	(version 20260206)
	(generator "pcbnew")
	(generator_version "10.0")
	(general
		(thickness 1.6)
		(legacy_teardrops no)
	)
	(paper "A4")
	(title_block
		(title "04192023_DAF0TMB3IC0_F0TG_MB_C_brd_V02_OCP.brd")
		(comment 1 "Grand Teton / footprints 7267-7268 of 8354")
	)
	(layers
		(0 "F.Cu" signal "TOP")
		(4 "In1.Cu" signal "GND")
		(6 "In2.Cu" signal "IN1")
		(8 "In3.Cu" signal "GND1")
		(10 "In4.Cu" signal "IN2")
		(12 "In5.Cu" signal "GND2")
		(14 "In6.Cu" signal "IN3")
		(16 "In7.Cu" signal "GND3")
		(18 "In8.Cu" signal "VCC")
		(20 "In9.Cu" signal "VCC1")
		(22 "In10.Cu" signal "GND4")
		(24 "In11.Cu" signal "IN4")
		(26 "In12.Cu" signal "GND5")
		(28 "In13.Cu" signal "IN5")
		(30 "In14.Cu" signal "GND6")
		(32 "In15.Cu" signal "IN6")
		(34 "In16.Cu" signal "GND7")
		(2 "B.Cu" signal "BOTTOM")
		(9 "F.Adhes" user "F.Adhesive")
		(11 "B.Adhes" user "B.Adhesive")
		(13 "F.Paste" user "Package Geometry/Pastemask Top")
		(15 "B.Paste" user "Package Geometry/Pastemask Bottom")
		(5 "F.SilkS" user "Ref Des/Silkscreen Top")
		(7 "B.SilkS" user "Ref Des/Silkscreen Bottom")
		(1 "F.Mask" user "Board Geometry/Soldermask Top")
		(3 "B.Mask" user "Board Geometry/Soldermask Bottom")
		(17 "Dwgs.User" user "User.Drawings")
		(19 "Cmts.User" user "User.Comments")
		(21 "Eco1.User" user "User.Eco1")
		(23 "Eco2.User" user "User.Eco2")
		(25 "Edge.Cuts" user "Board Geometry/Outline")
		(27 "Margin" user)
		(31 "F.CrtYd" user "Package Geometry/Place Bound Top")
		(29 "B.CrtYd" user "Package Geometry/Place Bound Bottom")
		(35 "F.Fab" user "Ref Des/Assembly Top")
		(33 "B.Fab" user "Ref Des/Assembly Bottom")
	)
	(footprint ""
		(layer "B.Cu")
		(at 172.456094 -417.078668)
		(property "Reference" "R2916"
			(at 0 0 0)
			(layer "B.SilkS")
			(hide yes)
			(effects
				(font
					(size 1.27 1.27)
				)
				(justify mirror)
			)
		)
		(property "Value" ""
			(at 0 0 0)
			(layer "B.Fab")
			(effects
				(font
					(size 1.27 1.27)
				)
				(justify mirror)
			)
		)
		(duplicate_pad_numbers_are_jumpers no)
		(fp_line
			(start -0.7874 -0.4064)
			(end -0.7874 0.4064)
			(stroke
				(width 0.1524)
				(type default)
			)
			(layer "B.SilkS")
		)
		(fp_line
			(start -0.7874 0.4064)
			(end 0.7874 0.4064)
			(stroke
				(width 0.1524)
				(type default)
			)
			(layer "B.SilkS")
		)
		(fp_line
			(start 0.7874 -0.4064)
			(end -0.7874 -0.4064)
			(stroke
				(width 0.1524)
				(type default)
			)
			(layer "B.SilkS")
		)
		(fp_line
			(start 0.7874 0.4064)
			(end 0.7874 -0.4064)
			(stroke
				(width 0.1524)
				(type default)
			)
			(layer "B.SilkS")
		)
		(fp_line
			(start -0.67945 -0.3048)
			(end -0.67945 0.3048)
			(stroke
				(width 0.1)
				(type default)
			)
			(layer "B.Fab")
		)
		(fp_line
			(start -0.67945 0.3048)
			(end -0.120396 0.3048)
			(stroke
				(width 0.1)
				(type default)
			)
			(layer "B.Fab")
		)
		(fp_line
			(start -0.12065 -0.3048)
			(end -0.67945 -0.3048)
			(stroke
				(width 0.1)
				(type default)
			)
			(layer "B.Fab")
		)
		(fp_line
			(start -0.12065 -0.2794)
			(end -0.12065 -0.3048)
			(stroke
				(width 0.1)
				(type default)
			)
			(layer "B.Fab")
		)
		(fp_line
			(start -0.120396 0.2794)
			(end 0.12065 0.2794)
			(stroke
				(width 0.1)
				(type default)
			)
			(layer "B.Fab")
		)
		(fp_line
			(start -0.120396 0.3048)
			(end -0.120396 0.2794)
			(stroke
				(width 0.1)
				(type default)
			)
			(layer "B.Fab")
		)
		(fp_line
			(start 0.12065 -0.305054)
			(end 0.12065 -0.2794)
			(stroke
				(width 0.1)
				(type default)
			)
			(layer "B.Fab")
		)
		(fp_line
			(start 0.12065 -0.2794)
			(end -0.12065 -0.2794)
			(stroke
				(width 0.1)
				(type default)
			)
			(layer "B.Fab")
		)
		(fp_line
			(start 0.12065 0.2794)
			(end 0.12065 0.3048)
			(stroke
				(width 0.1)
				(type default)
			)
			(layer "B.Fab")
		)
		(fp_line
			(start 0.12065 0.3048)
			(end 0.67945 0.3048)
			(stroke
				(width 0.1)
				(type default)
			)
			(layer "B.Fab")
		)
		(fp_line
			(start 0.67945 -0.305054)
			(end 0.12065 -0.305054)
			(stroke
				(width 0.1)
				(type default)
			)
			(layer "B.Fab")
		)
		(fp_line
			(start 0.67945 0.3048)
			(end 0.67945 -0.305054)
			(stroke
				(width 0.1)
				(type default)
			)
			(layer "B.Fab")
		)
		(pad "1" smd circle
			(at 0.40005 0 180)
			(size 0 0)
			(layers "B.Cu" "B.Mask" "B.Paste")
			(net "RST_SWB_BIC_R_N")
		)
		(pad "2" smd circle
			(at -0.40005 0 180)
			(size 0 0)
			(layers "B.Cu" "B.Mask" "B.Paste")
			(net "GND")
		)
	)
	(footprint ""
		(layer "B.Cu")
		(at 197.269608 -125.817376 180)
		(property "Reference" "R6113"
			(at 0 0 0)
			(layer "B.SilkS")
			(hide yes)
			(effects
				(font
					(size 1.27 1.27)
				)
				(justify mirror)
			)
		)
		(property "Value" ""
			(at 0 0 0)
			(layer "B.Fab")
			(effects
				(font
					(size 1.27 1.27)
				)
				(justify mirror)
			)
		)
		(duplicate_pad_numbers_are_jumpers no)
		(fp_line
			(start 0.7874 0.4064)
			(end 0.7874 -0.4064)
			(stroke
				(width 0.1524)
				(type default)
			)
			(layer "B.SilkS")
		)
		(fp_line
			(start 0.7874 -0.4064)
			(end -0.7874 -0.4064)
			(stroke
				(width 0.1524)
				(type default)
			)
			(layer "B.SilkS")
		)
		(fp_line
			(start -0.7874 0.4064)
			(end 0.7874 0.4064)
			(stroke
				(width 0.1524)
				(type default)
			)
			(layer "B.SilkS")
		)
		(fp_line
			(start -0.7874 -0.4064)
			(end -0.7874 0.4064)
			(stroke
				(width 0.1524)
				(type default)
			)
			(layer "B.SilkS")
		)
		(fp_line
			(start 0.67945 0.3048)
			(end 0.67945 -0.305054)
			(stroke
				(width 0.1)
				(type default)
			)
			(layer "B.Fab")
		)
		(fp_line
			(start 0.67945 -0.305054)
			(end 0.12065 -0.305054)
			(stroke
				(width 0.1)
				(type default)
			)
			(layer "B.Fab")
		)
		(fp_line
			(start 0.12065 0.3048)
			(end 0.67945 0.3048)
			(stroke
				(width 0.1)
				(type default)
			)
			(layer "B.Fab")
		)
		(fp_line
			(start 0.12065 0.2794)
			(end 0.12065 0.3048)
			(stroke
				(width 0.1)
				(type default)
			)
			(layer "B.Fab")
		)
		(fp_line
			(start 0.12065 -0.2794)
			(end -0.12065 -0.2794)
			(stroke
				(width 0.1)
				(type default)
			)
			(layer "B.Fab")
		)
		(fp_line
			(start 0.12065 -0.305054)
			(end 0.12065 -0.2794)
			(stroke
				(width 0.1)
				(type default)
			)
			(layer "B.Fab")
		)
		(fp_line
			(start -0.120396 0.3048)
			(end -0.120396 0.2794)
			(stroke
				(width 0.1)
				(type default)
			)
			(layer "B.Fab")
		)
		(fp_line
			(start -0.120396 0.2794)
			(end 0.12065 0.2794)
			(stroke
				(width 0.1)
				(type default)
			)
			(layer "B.Fab")
		)
		(fp_line
			(start -0.12065 -0.2794)
			(end -0.12065 -0.3048)
			(stroke
				(width 0.1)
				(type default)
			)
			(layer "B.Fab")
		)
		(fp_line
			(start -0.12065 -0.3048)
			(end -0.67945 -0.3048)
			(stroke
				(width 0.1)
				(type default)
			)
			(layer "B.Fab")
		)
		(fp_line
			(start -0.67945 0.3048)
			(end -0.120396 0.3048)
			(stroke
				(width 0.1)
				(type default)
			)
			(layer "B.Fab")
		)
		(fp_line
			(start -0.67945 -0.3048)
			(end -0.67945 0.3048)
			(stroke
				(width 0.1)
				(type default)
			)
			(layer "B.Fab")
		)
		(pad "1" smd circle
			(at 0.40005 0)
			(size 0 0)
			(layers "B.Cu" "B.Mask" "B.Paste")
			(net "RST_PERST_CPU1_SWB_N")
		)
		(pad "2" smd circle
			(at -0.40005 0)
			(size 0 0)
			(layers "B.Cu" "B.Mask" "B.Paste")
			(net "RST_PERST_CPU1_SWB_R_N")
		)
	)
)
